FILE_TYPE = MACRO_DRAWING;
SET COLOR_WIRE YELLOW;
SET COLOR_PROP ORANGE;
SET COLOR_DOT WHITE;
SET COLOR_ARC YELLOW;
SET COLOR_BODY GREEN;
SET COLOR_NOTE PURPLE;
SET PROP_DISPLAY VALUE;
SET PAGE_NUMBER P444;
FORCEADD QUANTA_TITLE_BLOCK_C..1
(0 0);
FORCEPROP 1 LAST CUSTOM_TXT_CDS <NAME_2>
J 0
(-3175 50);
FORCEPROP 1 LAST CUSTOM_TXT_CDS <NAME_1>
J 0
(-3175 175);
FORCEPROP 1 LAST CUSTOM_TXT_CDS <Q_NUMBER>
J 0
(-1403 103);
DISPLAY 1.212766 (-1403 103);
FORCEPROP 1 LAST CUSTOM_TXT_CDS <Q_PROJ>
J 0
(-2382 102);
DISPLAY 1.212766 (-2382 102);
FORCEPROP 1 LAST CUSTOM_TXT_CDS <Q_REV>
J 0
(-184 103);
DISPLAY 1.212766 (-184 103);
FORCEPROP 1 LAST CUSTOM_TXT_CDS <CON_LAST_MODIFIED>
J 0
(-1885 15);
DISPLAY 0.978723 (-1885 15);
FORCEPROP 1 LAST CUSTOM_TXT_CDS <CON_PAGE_NUM> OF <CON_TOTAL_PAGES>
J 0
(-446 18);
DISPLAY 0.978723 (-446 18);
FORCEPROP 1 LAST Q_TITLE RETIMER_CPU1_P1(9)
J 0
(-9366 26);
DISPLAY 2.446809 (-9366 26);
PAINT GREEN (-9366 26);
FORCEPROP 1 LAST CDS_LMAN_SYM_OUTLINE -9475,6775,100,-125
J 0
(0 0);
DISPLAY 0.468085 (0 0);
PAINT GREEN (0 0);
DISPLAY INVISIBLE (0 0);
FORCEPROP 2 LAST CDS_LIB pure_quanta
J 0
(0 0);
DISPLAY INVISIBLE (0 0);
FORCEPROP 2 LAST PAGE_BORDER TRUE
J 0
(-7890 5250);
DISPLAY 0.638298 (-7890 5250);
PAINT PINK (-7890 5250);
DISPLAY INVISIBLE (-7890 5250);
FORCEPROP 2 LAST CDS_XR_PAGE_TITLE CR-336 : @T6G_MB_LIB.T6G(SCH_1):PAGE336
J 0
(-7890 5250);
DISPLAY 0.638298 (-7890 5250);
PAINT PINK (-7890 5250);
DISPLAY INVISIBLE (-7890 5250);
FORCEPROP 2 LAST CUSTOM_TXT_CDS <XR_PAGE_TITLE>
J 0
(-7890 5250);
DISPLAY 0.638298 (-7890 5250);
PAINT PINK (-7890 5250);
DISPLAY INVISIBLE (-7890 5250);
FORCEPROP 1 LAST COMMENT_BODY TRUE
J 0
(12 -13);
DISPLAY 0.978723 (12 -13);
PAINT GREEN (12 -13);
DISPLAY INVISIBLE (12 -13);
FORCEPROP 1 LAST Q_DEPT BU9
J 1
(-3763 49);
DISPLAY 1.957447 (-3763 49);
PAINT GREEN (-3763 49);
DISPLAY INVISIBLE (-3763 49);
FORCEPROP 0 LAST CDS_CON_LAST_MODIFIED Thu Aug 24 10:16:54 2023
J 0
(-1885 15);
DISPLAY INVISIBLE (-1885 15);
QUIT
